(kicad_pcb
	(version 20241229)
	(generator "pcbnew")
	(generator_version "9.0")
	(general
		(thickness 1.6642)
		(legacy_teardrops no)
	)
	(paper "A3")
	(title_block
		(title "PolarFire SoM")
		(date "2025-07-22")
		(rev "1.1.4")
		(company "Antmicro Ltd")
		(comment 1 "www.antmicro.com")
		(comment 9 "footprint 85 of 470 (U1), pads 68-134 of 484")
	)
	(layers
		(0 "F.Cu" mixed)
		(4 "In1.Cu" power)
		(6 "In2.Cu" signal)
		(8 "In3.Cu" power)
		(10 "In4.Cu" signal)
		(12 "In5.Cu" power)
		(14 "In6.Cu" power)
		(16 "In7.Cu" signal)
		(18 "In8.Cu" power)
		(20 "In9.Cu" signal)
		(22 "In10.Cu" power)
		(24 "In11.Cu" signal)
		(26 "In12.Cu" signal)
		(2 "B.Cu" mixed)
		(9 "F.Adhes" user "F.Adhesive")
		(11 "B.Adhes" user "B.Adhesive")
		(13 "F.Paste" user)
		(15 "B.Paste" user)
		(5 "F.SilkS" user "F.Silkscreen")
		(7 "B.SilkS" user "B.Silkscreen")
		(1 "F.Mask" user)
		(3 "B.Mask" user)
		(17 "Dwgs.User" user "User.Drawings")
		(19 "Cmts.User" user "User.Comments")
		(21 "Eco1.User" user "User.Eco1")
		(23 "Eco2.User" user "User.Eco2")
		(25 "Edge.Cuts" user)
		(27 "Margin" user)
		(31 "F.CrtYd" user "F.Courtyard")
		(29 "B.CrtYd" user "B.Courtyard")
		(35 "F.Fab" user)
		(33 "B.Fab" user)
	)
	(footprint "antmicro-footprints:BGA-484_19x19mm_Layout22x22_P0.8mm_FCVG484"
		(layer "F.Cu")
		(at 197.699 132.701 -90)
		(descr "FCVG484, 19.0x19.0mm, 484 Ball, 22x22 Layout, 0.8mm Pitch")
		(tags "BGA 484 0.8")
		(property "Reference" "U1"
			(at 0 -10.8 270)
			(layer "F.SilkS")
			(effects
				(font
					(size 0.7 0.7)
					(thickness 0.15)
				)
				(justify left bottom)
			)
		)
		(property "Value" "MPFS250T-FCVG484"
			(at 0 11.5 270)
			(layer "F.Fab")
			(hide yes)
			(effects
				(font
					(size 0.7 0.7)
					(thickness 0.15)
				)
				(justify left bottom)
			)
		)
		(property "Datasheet" "https://ww1.microchip.com/downloads/aemDocuments/documents/FPGA/ProductDocuments/DataSheets/PolarFire-SoC-Datasheet-DS00004248.pdf"
			(at 0 0 270)
			(layer "F.Fab")
			(hide yes)
			(effects
				(font
					(size 1.27 1.27)
					(thickness 0.15)
				)
			)
		)
		(property "Description" "RISC-V System On Chip (SOC) IC PolarFire® FPGA - 254K Logic Modules 484-FCBGA (19x19)"
			(at 0 0 270)
			(layer "F.Fab")
			(hide yes)
			(effects
				(font
					(size 1.27 1.27)
					(thickness 0.15)
				)
			)
		)
		(property "MPN" "MPFS250T-FCVG484E"
			(at 0 0 270)
			(unlocked yes)
			(layer "F.Fab")
			(hide yes)
			(effects
				(font
					(size 1 1)
					(thickness 0.15)
				)
			)
		)
		(property "Manufacturer" "Microchip Technology"
			(at 0 0 270)
			(unlocked yes)
			(layer "F.Fab")
			(hide yes)
			(effects
				(font
					(size 1 1)
					(thickness 0.15)
				)
			)
		)
		(property "VSD_class" "MPFS250T"
			(at 0 0 270)
			(unlocked yes)
			(layer "F.Fab")
			(hide yes)
			(effects
				(font
					(size 1 1)
					(thickness 0.15)
				)
			)
		)
		(property "Author" "Antmicro"
			(at 0 0 270)
			(unlocked yes)
			(layer "F.Fab")
			(hide yes)
			(effects
				(font
					(size 1 1)
					(thickness 0.15)
				)
			)
		)
		(property "License" "Apache-2.0"
			(at 0 0 270)
			(unlocked yes)
			(layer "F.Fab")
			(hide yes)
			(effects
				(font
					(size 1 1)
					(thickness 0.15)
				)
			)
		)
		(sheetname "/FPGA Config/")
		(sheetfile "fpga-config.kicad_sch")
		(attr smd)
		(pad "B2" smd circle
			(at -7.6 -7.6 270)
			(size 0.45 0.45)
			(layers "F.Cu" "F.Mask" "F.Paste")
			(net 371 "unconnected-(U1C-MSSIO32B2-PadB2)")
			(pinfunction "MSSIO32B2")
			(pintype "bidirectional+no_connect")
			(die_length 10.9065)
		)
		(pad "B3" smd circle
			(at -6.8 -7.6 270)
			(size 0.45 0.45)
			(layers "F.Cu" "F.Mask" "F.Paste")
			(net 372 "unconnected-(U1C-MSSIO34B2-PadB3)")
			(pinfunction "MSSIO34B2")
			(pintype "bidirectional+no_connect")
			(die_length 10.3654)
		)
		(pad "B4" smd circle
			(at -6 -7.6 270)
			(size 0.45 0.45)
			(layers "F.Cu" "F.Mask" "F.Paste")
			(net 86 "/FPGA GPIO/HDMI_FPGA.TX0_N")
			(pinfunction "GPIO169NB1")
			(pintype "bidirectional")
			(die_length 6.68841)
		)
		(pad "B5" smd circle
			(at -5.201 -7.6 270)
			(size 0.45 0.45)
			(layers "F.Cu" "F.Mask" "F.Paste")
			(net 83 "/FPGA GPIO/HDMI_FPGA.TX1_N")
			(pinfunction "GPIO170NB1/DQS")
			(pintype "bidirectional")
			(die_length 6.42359)
		)
		(pad "B6" smd circle
			(at -4.401 -7.6 270)
			(size 0.45 0.45)
			(layers "F.Cu" "F.Mask" "F.Paste")
			(net 649 "VDD")
			(pinfunction "VDDI1")
			(pintype "passive")
		)
		(pad "B7" smd circle
			(at -3.601 -7.6 270)
			(size 0.45 0.45)
			(layers "F.Cu" "F.Mask" "F.Paste")
			(net 373 "unconnected-(U1B-GPIO173NB1-PadB7)")
			(pinfunction "GPIO173NB1")
			(pintype "bidirectional+no_connect")
			(die_length 6.39951)
		)
		(pad "B8" smd circle
			(at -2.8 -7.6 270)
			(size 0.45 0.45)
			(layers "F.Cu" "F.Mask" "F.Paste")
			(net 353 "/FPGA GPIO/HDMI0_SCL_SRC")
			(pinfunction "GPIO175NB1")
			(pintype "bidirectional")
			(die_length 6.72389)
		)
		(pad "B9" smd circle
			(at -2 -7.6 270)
			(size 0.45 0.45)
			(layers "F.Cu" "F.Mask" "F.Paste")
			(net 345 "/FPGA GPIO/Crosslink.CS")
			(pinfunction "GPIO179NB1")
			(pintype "bidirectional")
			(die_length 7.41584)
		)
		(pad "B10" smd circle
			(at -1.2 -7.6 270)
			(size 0.45 0.45)
			(layers "F.Cu" "F.Mask" "F.Paste")
			(net 346 "/FPGA GPIO/Crosslink.MOSI")
			(pinfunction "GPIO179PB1")
			(pintype "bidirectional")
			(die_length 7.43586)
		)
		(pad "B11" smd circle
			(at -0.401 -7.6 270)
			(size 0.45 0.45)
			(layers "F.Cu" "F.Mask" "F.Paste")
			(net 417 "GND")
			(pinfunction "VSS")
			(pintype "passive")
		)
		(pad "B12" smd circle
			(at 0.4 -7.6 270)
			(size 0.45 0.45)
			(layers "F.Cu" "F.Mask" "F.Paste")
			(net 111 "/Bottom Connector/CAM0.D0_P")
			(pinfunction "GPIO0PB1/CLKIN_S_4")
			(pintype "bidirectional")
			(die_length 7.45678)
		)
		(pad "B13" smd circle
			(at 1.199 -7.6 270)
			(size 0.45 0.45)
			(layers "F.Cu" "F.Mask" "F.Paste")
			(net 120 "/Bottom Connector/CAM0.C_P")
			(pinfunction "GPIO3PB1/CLKIN_S_6")
			(pintype "bidirectional")
			(die_length 7.81993)
		)
		(pad "B14" smd circle
			(at 1.999 -7.6 270)
			(size 0.45 0.45)
			(layers "F.Cu" "F.Mask" "F.Paste")
			(net 118 "/Bottom Connector/CAM0.C_N")
			(pinfunction "GPIO3NB1")
			(pintype "bidirectional")
			(die_length 7.83621)
		)
		(pad "B15" smd circle
			(at 2.799 -7.6 270)
			(size 0.45 0.45)
			(layers "F.Cu" "F.Mask" "F.Paste")
			(net 349 "/FPGA GPIO/PF_ETH_MDIO")
			(pinfunction "GPIO5NB1")
			(pintype "bidirectional")
			(die_length 7.64736)
		)
		(pad "B16" smd circle
			(at 3.6 -7.6 270)
			(size 0.45 0.45)
			(layers "F.Cu" "F.Mask" "F.Paste")
			(net 649 "VDD")
			(pinfunction "VDDI1")
			(pintype "passive")
		)
		(pad "B17" smd circle
			(at 4.4 -7.6 270)
			(size 0.45 0.45)
			(layers "F.Cu" "F.Mask" "F.Paste")
			(net 24 "SPI6_MISO{slash}RPI_GPIO19")
			(pinfunction "GPIO15PB1/CCC_SE_CLKIN_S_10/CCC_SE_PLL1_OUT0")
			(pintype "bidirectional")
			(die_length 10.4627)
		)
		(pad "B18" smd circle
			(at 5.2 -7.6 270)
			(size 0.45 0.45)
			(layers "F.Cu" "F.Mask" "F.Paste")
			(net 26 "GPIO27")
			(pinfunction "GPIO17NB1")
			(pintype "bidirectional")
			(die_length 10.8909)
		)
		(pad "B19" smd circle
			(at 5.999 -7.6 270)
			(size 0.45 0.45)
			(layers "F.Cu" "F.Mask" "F.Paste")
			(net 354 "/FPGA GPIO/WiFi_DATA_2")
			(pinfunction "GPIO19NB9")
			(pintype "bidirectional")
			(die_length 9.83847)
		)
		(pad "B20" smd circle
			(at 6.799 -7.6 270)
			(size 0.45 0.45)
			(layers "F.Cu" "F.Mask" "F.Paste")
			(net 355 "/FPGA GPIO/WiFi_DATA_1")
			(pinfunction "GPIO19PB9")
			(pintype "bidirectional")
			(die_length 9.84464)
		)
		(pad "B21" smd circle
			(at 7.599 -7.6 270)
			(size 0.45 0.45)
			(layers "F.Cu" "F.Mask" "F.Paste")
			(net 350 "/FPGA GPIO/SCL0_PF")
			(pinfunction "GPIO22PB9")
			(pintype "bidirectional")
			(die_length 10.6697)
		)
		(pad "B22" smd circle
			(at 8.4 -7.6 270)
			(size 0.45 0.45)
			(layers "F.Cu" "F.Mask" "F.Paste")
			(net 509 "/FPGA GPIO/SDA0_PF")
			(pinfunction "GPIO22NB9")
			(pintype "bidirectional")
			(die_length 10.6676)
		)
		(pad "C1" smd circle
			(at -8.401 -6.8 270)
			(size 0.45 0.45)
			(layers "F.Cu" "F.Mask" "F.Paste")
			(net 92 "/FPGA MSSIO/SUPPLY.SCL")
			(pinfunction "MSSIO26B2")
			(pintype "bidirectional")
			(die_length 10.9779)
		)
		(pad "C2" smd circle
			(at -7.6 -6.8 270)
			(size 0.45 0.45)
			(layers "F.Cu" "F.Mask" "F.Paste")
			(net 383 "unconnected-(U1C-MSSIO29B2-PadC2)")
			(pinfunction "MSSIO29B2")
			(pintype "bidirectional+no_connect")
			(die_length 10.7338)
		)
		(pad "C3" smd circle
			(at -6.8 -6.8 270)
			(size 0.45 0.45)
			(layers "F.Cu" "F.Mask" "F.Paste")
			(net 649 "VDD")
			(pinfunction "VDDI2")
			(pintype "power_in")
		)
		(pad "C4" smd circle
			(at -6 -6.8 270)
			(size 0.45 0.45)
			(layers "F.Cu" "F.Mask" "F.Paste")
			(net 87 "/FPGA GPIO/HDMI_FPGA.TX0_P")
			(pinfunction "GPIO169PB1/CCC_SW_CLKIN_S_1")
			(pintype "bidirectional")
			(die_length 6.70234)
		)
		(pad "C5" smd circle
			(at -5.201 -6.8 270)
			(size 0.45 0.45)
			(layers "F.Cu" "F.Mask" "F.Paste")
			(net 84 "/FPGA GPIO/HDMI_FPGA.TX1_P")
			(pinfunction "GPIO170PB1/DQS/CCC_SW_PLL1_OUT0")
			(pintype "bidirectional")
			(die_length 6.43731)
		)
		(pad "C6" smd circle
			(at -4.401 -6.8 270)
			(size 0.45 0.45)
			(layers "F.Cu" "F.Mask" "F.Paste")
			(net 11 "GPIO16")
			(pinfunction "GPIO171PB1/CLKIN_S_2/CCC_SW_CLKIN_S_2/CCC_SW_PLL1_OUT0")
			(pintype "bidirectional")
			(die_length 6.13895)
		)
		(pad "C7" smd circle
			(at -3.601 -6.8 270)
			(size 0.45 0.45)
			(layers "F.Cu" "F.Mask" "F.Paste")
			(net 375 "unconnected-(U1B-GPIO171NB1-PadC7)")
			(pinfunction "GPIO171NB1")
			(pintype "bidirectional+no_connect")
			(die_length 6.14822)
		)
		(pad "C8" smd circle
			(at -2.8 -6.8 270)
			(size 0.45 0.45)
			(layers "F.Cu" "F.Mask" "F.Paste")
			(net 417 "GND")
			(pinfunction "VSS")
			(pintype "passive")
		)
		(pad "C9" smd circle
			(at -2 -6.8 270)
			(size 0.45 0.45)
			(layers "F.Cu" "F.Mask" "F.Paste")
			(net 356 "/FPGA GPIO/HDMI0_HPD_SRC")
			(pinfunction "GPIO176NB1/DQS")
			(pintype "bidirectional")
			(die_length 7.80518)
		)
		(pad "C10" smd circle
			(at -1.2 -6.8 270)
			(size 0.45 0.45)
			(layers "F.Cu" "F.Mask" "F.Paste")
			(net 18 "GPIO11")
			(pinfunction "GPIO176PB1/DQS/CCC_SW_PLL0_OUT0")
			(pintype "bidirectional")
			(die_length 7.81684)
		)
		(pad "C11" smd circle
			(at -0.401 -6.8 270)
			(size 0.45 0.45)
			(layers "F.Cu" "F.Mask" "F.Paste")
			(net 559 "unconnected-(U1B-GPIO178PB1{slash}CCC_SW_PLL0_OUT1-PadC11)")
			(pinfunction "GPIO178PB1/CCC_SW_PLL0_OUT1")
			(pintype "bidirectional+no_connect")
			(die_length 8.84089)
		)
		(pad "C12" smd circle
			(at 0.4 -6.8 270)
			(size 0.45 0.45)
			(layers "F.Cu" "F.Mask" "F.Paste")
			(net 109 "/Bottom Connector/CAM0.D0_N")
			(pinfunction "GPIO0NB1")
			(pintype "bidirectional")
			(die_length 7.46342)
		)
		(pad "C13" smd circle
			(at 1.199 -6.8 270)
			(size 0.45 0.45)
			(layers "F.Cu" "F.Mask" "F.Paste")
			(net 649 "VDD")
			(pinfunction "VDDI1")
			(pintype "passive")
		)
		(pad "C14" smd circle
			(at 1.999 -6.8 270)
			(size 0.45 0.45)
			(layers "F.Cu" "F.Mask" "F.Paste")
			(net 376 "unconnected-(U1B-GPIO4PB1{slash}LPRB_A-PadC14)")
			(pinfunction "GPIO4PB1/LPRB_A")
			(pintype "bidirectional+no_connect")
			(die_length 8.46872)
		)
		(pad "C15" smd circle
			(at 2.799 -6.8 270)
			(size 0.45 0.45)
			(layers "F.Cu" "F.Mask" "F.Paste")
			(net 377 "unconnected-(U1B-GPIO4NB1{slash}LPRB_B-PadC15)")
			(pinfunction "GPIO4NB1/LPRB_B")
			(pintype "bidirectional+no_connect")
			(die_length 8.50071)
		)
		(pad "C16" smd circle
			(at 3.6 -6.8 270)
			(size 0.45 0.45)
			(layers "F.Cu" "F.Mask" "F.Paste")
			(net 177 "SDA1{slash}RPI_GPIO02")
			(pinfunction "GPIO12PB1")
			(pintype "bidirectional")
			(die_length 10.1134)
		)
		(pad "C17" smd circle
			(at 4.4 -6.8 270)
			(size 0.45 0.45)
			(layers "F.Cu" "F.Mask" "F.Paste")
			(net 25 "SPI6_MOSI{slash}RPI_GPIO20")
			(pinfunction "GPIO15NB1")
			(pintype "bidirectional")
			(die_length 10.4762)
		)
		(pad "C18" smd circle
			(at 5.2 -6.8 270)
			(size 0.45 0.45)
			(layers "F.Cu" "F.Mask" "F.Paste")
			(net 417 "GND")
			(pinfunction "VSS")
			(pintype "passive")
		)
		(pad "C19" smd circle
			(at 5.999 -6.8 270)
			(size 0.45 0.45)
			(layers "F.Cu" "F.Mask" "F.Paste")
			(net 358 "/FPGA GPIO/WiFi_CMD")
			(pinfunction "GPIO18PB9")
			(pintype "bidirectional")
			(die_length 9.19379)
		)
		(pad "C20" smd circle
			(at 6.799 -6.8 270)
			(size 0.45 0.45)
			(layers "F.Cu" "F.Mask" "F.Paste")
			(net 374 "/FPGA GPIO/WiFi_DATA_0")
			(pinfunction "GPIO18NB9")
			(pintype "bidirectional")
			(die_length 9.14934)
		)
		(pad "C21" smd circle
			(at 7.599 -6.8 270)
			(size 0.45 0.45)
			(layers "F.Cu" "F.Mask" "F.Paste")
			(net 649 "VDD")
			(pinfunction "VDDI1")
			(pintype "passive")
		)
		(pad "C22" smd circle
			(at 8.4 -6.8 270)
			(size 0.45 0.45)
			(layers "F.Cu" "F.Mask" "F.Paste")
			(net 378 "unconnected-(U1B-GPIO23PB9-PadC22)")
			(pinfunction "GPIO23PB9")
			(pintype "bidirectional+no_connect")
			(die_length 10.3467)
		)
		(pad "D1" smd circle
			(at -8.401 -6 270)
			(size 0.45 0.45)
			(layers "F.Cu" "F.Mask" "F.Paste")
			(net 637 "/FPGA GPIO/ULPI.DATA4")
			(pinfunction "MSSIO22B2")
			(pintype "bidirectional")
			(die_length 10.1837)
		)
		(pad "D2" smd circle
			(at -7.6 -6 270)
			(size 0.45 0.45)
			(layers "F.Cu" "F.Mask" "F.Paste")
			(net 638 "/FPGA GPIO/ULPI.DATA5")
			(pinfunction "MSSIO23B2")
			(pintype "bidirectional")
			(die_length 9.99134)
		)
		(pad "D3" smd circle
			(at -6.8 -6 270)
			(size 0.45 0.45)
			(layers "F.Cu" "F.Mask" "F.Paste")
			(net 284 "unconnected-(U1C-MSSIO28B2-PadD3)")
			(pinfunction "MSSIO28B2")
			(pintype "bidirectional+no_connect")
			(die_length 9.49076)
		)
		(pad "D4" smd circle
			(at -6 -6 270)
			(size 0.45 0.45)
			(layers "F.Cu" "F.Mask" "F.Paste")
			(net 380 "unconnected-(U1C-MSSIO37B2-PadD4)")
			(pinfunction "MSSIO37B2")
			(pintype "bidirectional+no_connect")
			(die_length 9.41653)
		)
		(pad "D5" smd circle
			(at -5.201 -6 270)
			(size 0.45 0.45)
			(layers "F.Cu" "F.Mask" "F.Paste")
			(net 417 "GND")
			(pinfunction "VSS")
			(pintype "passive")
		)
		(pad "D6" smd circle
			(at -4.401 -6 270)
			(size 0.45 0.45)
			(layers "F.Cu" "F.Mask" "F.Paste")
			(net 27 "UART5_TX{slash}RPI_GPIO13")
			(pinfunction "GPIO168NB1")
			(pintype "bidirectional")
			(die_length 5.98256)
		)
		(pad "D7" smd circle
			(at -3.601 -6 270)
			(size 0.45 0.45)
			(layers "F.Cu" "F.Mask" "F.Paste")
			(net 381 "unconnected-(U1B-GPIO168PB1{slash}CCC_SW_CLKIN_S_0-PadD7)")
			(pinfunction "GPIO168PB1/CCC_SW_CLKIN_S_0")
			(pintype "bidirectional+no_connect")
			(die_length 5.98411)
		)
		(pad "D8" smd circle
			(at -2.8 -6 270)
			(size 0.45 0.45)
			(layers "F.Cu" "F.Mask" "F.Paste")
			(net 60 "/FPGA GPIO/HDMI_FPGA.TX2_N")
			(pinfunction "GPIO174NB1")
			(pintype "bidirectional")
			(die_length 7.07352)
		)
		(pad "D9" smd circle
			(at -2 -6 270)
			(size 0.45 0.45)
			(layers "F.Cu" "F.Mask" "F.Paste")
			(net 82 "/FPGA GPIO/HDMI_FPGA.TX2_P")
			(pinfunction "GPIO174PB1")
			(pintype "bidirectional")
			(die_length 7.0517)
		)
		(pad "D10" smd circle
			(at -1.2 -6 270)
			(size 0.45 0.45)
			(layers "F.Cu" "F.Mask" "F.Paste")
			(net 649 "VDD")
			(pinfunction "VDDI1")
			(pintype "passive")
		)
		(pad "D11" smd circle
			(at -0.401 -6 270)
			(size 0.45 0.45)
			(layers "F.Cu" "F.Mask" "F.Paste")
			(net 537 "/FPGA GPIO/Crosslink.SDA")
			(pinfunction "GPIO178NB1")
			(pintype "bidirectional")
			(die_length 8.80638)
		)
		(pad "D12" smd circle
			(at 0.4 -6 270)
			(size 0.45 0.45)
			(layers "F.Cu" "F.Mask" "F.Paste")
			(net 342 "/FPGA GPIO/USER_LED_R")
			(pinfunction "GPIO183PB1")
			(pintype "bidirectional")
			(die_length 11.0319)
		)
		(pad "D13" smd circle
			(at 1.199 -6 270)
			(size 0.45 0.45)
			(layers "F.Cu" "F.Mask" "F.Paste")
			(net 89 "/FPGA GPIO/HDMI_FPGA.CLK_P")
			(pinfunction "GPIO2PB1/DQS")
			(pintype "bidirectional")
			(die_length 8.05981)
		)
		(pad "D14" smd circle
			(at 1.999 -6 270)
			(size 0.45 0.45)
			(layers "F.Cu" "F.Mask" "F.Paste")
			(net 88 "/FPGA GPIO/HDMI_FPGA.CLK_N")
			(pinfunction "GPIO2NB1/DQS")
			(pintype "bidirectional")
			(die_length 8.06844)
		)
		(pad "D15" smd circle
			(at 2.799 -6 270)
			(size 0.45 0.45)
			(layers "F.Cu" "F.Mask" "F.Paste")
			(net 417 "GND")
			(pinfunction "VSS")
			(pintype "passive")
		)
		(pad "D16" smd circle
			(at 3.6 -6 270)
			(size 0.45 0.45)
			(layers "F.Cu" "F.Mask" "F.Paste")
			(net 382 "unconnected-(U1B-GPIO10NB1-PadD16)")
			(pinfunction "GPIO10NB1")
			(pintype "bidirectional+no_connect")
			(die_length 10.5394)
		)
		(pad "D17" smd circle
			(at 4.4 -6 270)
			(size 0.45 0.45)
			(layers "F.Cu" "F.Mask" "F.Paste")
			(net 174 "SCL1{slash}RPI_GPIO03")
			(pinfunction "GPIO12NB1")
			(pintype "bidirectional")
			(die_length 10.1368)
		)
		(pad "D18" smd circle
			(at 5.2 -6 270)
			(size 0.45 0.45)
			(layers "F.Cu" "F.Mask" "F.Paste")
			(net 20 "SPI6_SCLK{slash}RPI_GPIO21")
			(pinfunction "GPIO16PB1/CCC_SE_PLL1_OUT1")
			(pintype "bidirectional")
			(die_length 10.3636)
		)
		(pad "D19" smd circle
			(at 5.999 -6 270)
			(size 0.45 0.45)
			(layers "F.Cu" "F.Mask" "F.Paste")
			(net 29 "UART5_TX{slash}RPI_GPIO12")
			(pinfunction "GPIO14NB1/DQS")
			(pintype "bidirectional")
			(die_length 10.7354)
		)
		(pad "D20" smd circle
			(at 6.799 -6 270)
			(size 0.45 0.45)
			(layers "F.Cu" "F.Mask" "F.Paste")
			(net 543 "/FPGA GPIO/PCIe_nRST_PF")
			(pinfunction "GPIO21NB9")
			(pintype "bidirectional")
			(die_length 9.54946)
		)
		(pad "D21" smd circle
			(at 7.599 -6 270)
			(size 0.45 0.45)
			(layers "F.Cu" "F.Mask" "F.Paste")
			(net 544 "/FPGA GPIO/PCIe_CLK_nREQ_PF")
			(pinfunction "GPIO21PB9")
			(pintype "bidirectional")
			(die_length 9.60192)
		)
		(pad "D22" smd circle
			(at 8.4 -6 270)
			(size 0.45 0.45)
			(layers "F.Cu" "F.Mask" "F.Paste")
			(net 635 "/FPGA GPIO/ULPI.RESET")
			(pinfunction "GPIO23NB9")
			(pintype "bidirectional")
			(die_length 10.342)
		)
		(pad "E1" smd circle
			(at -8.401 -5.201 270)
			(size 0.45 0.45)
			(layers "F.Cu" "F.Mask" "F.Paste")
			(net 639 "/FPGA GPIO/ULPI.DATA1")
			(pinfunction "MSSIO19B2")
			(pintype "bidirectional")
			(die_length 9.80097)
		)
		(pad "E2" smd circle
			(at -7.6 -5.201 270)
			(size 0.45 0.45)
			(layers "F.Cu" "F.Mask" "F.Paste")
			(net 417 "GND")
			(pinfunction "VSS")
			(pintype "passive")
		)
	)
)
